(kicad_pcb
	(version 20241229)
	(generator "pcbnew")
	(generator_version "9.0")
	(general
		(thickness 1.6296)
		(legacy_teardrops no)
	)
	(paper "A3")
	(title_block
		(title "Thunderbolt to 10GbE adapter")
		(date "2026-04-21")
		(rev "1.1.0")
		(company "Antmicro Ltd")
		(comment 1 "www.antmicro.com")
		(comment 9 "footprints 262-265 of 703")
	)
	(layers
		(0 "F.Cu" signal)
		(4 "In1.Cu" signal)
		(6 "In2.Cu" signal)
		(8 "In3.Cu" signal)
		(10 "In4.Cu" signal)
		(12 "In5.Cu" signal)
		(14 "In6.Cu" signal)
		(2 "B.Cu" signal)
		(9 "F.Adhes" user "F.Adhesive")
		(11 "B.Adhes" user "B.Adhesive")
		(13 "F.Paste" user)
		(15 "B.Paste" user)
		(5 "F.SilkS" user "F.Silkscreen")
		(7 "B.SilkS" user "B.Silkscreen")
		(1 "F.Mask" user)
		(3 "B.Mask" user)
		(17 "Dwgs.User" user "User.Drawings")
		(19 "Cmts.User" user "User.Comments")
		(21 "Eco1.User" user "User.Eco1")
		(23 "Eco2.User" user "User.Eco2")
		(25 "Edge.Cuts" user)
		(27 "Margin" user)
		(31 "F.CrtYd" user "F.Courtyard")
		(29 "B.CrtYd" user "B.Courtyard")
		(35 "F.Fab" user)
		(33 "B.Fab" user)
	)
	(footprint "antmicro-footprints:LED_0603_1608Metric_G"
		(layer "F.Cu")
		(at 116.2 114.4 90)
		(descr "LED SMD 0603 Green")
		(tags "LED SMD 0603 Green")
		(property "Reference" "D4"
			(at -1.6 1.05 90)
			(layer "F.SilkS")
			(effects
				(font
					(size 0.7 0.7)
					(thickness 0.15)
				)
			)
		)
		(property "Value" "LED_G_0603_KP-1608CGCK"
			(at -0.001 1.599 90)
			(layer "F.Fab")
			(effects
				(font
					(size 0.7 0.7)
					(thickness 0.15)
				)
				(justify left bottom)
			)
		)
		(property "Datasheet" "http://www.kingbright.com/attachments/file/psearch//000/00/00/KP-1608CGCK(Ver.23B).pdf"
			(at 0 0 90)
			(layer "F.Fab")
			(hide yes)
			(effects
				(font
					(size 1.27 1.27)
					(thickness 0.15)
				)
			)
		)
		(property "Description" "LED, Green, SMD, 0603, 20 mA, 2.1 V, 570 nm"
			(at 0 0 90)
			(layer "F.Fab")
			(hide yes)
			(effects
				(font
					(size 1.27 1.27)
					(thickness 0.15)
				)
			)
		)
		(property "MPN" "KP-1608CGCK"
			(at 0 0 90)
			(unlocked yes)
			(layer "F.Fab")
			(hide yes)
			(effects
				(font
					(size 1 1)
					(thickness 0.15)
				)
			)
		)
		(property "Manufacturer" "Kingbright"
			(at 0 0 90)
			(unlocked yes)
			(layer "F.Fab")
			(hide yes)
			(effects
				(font
					(size 1 1)
					(thickness 0.15)
				)
			)
		)
		(property "License" "Apache-2.0"
			(at 0 0 90)
			(unlocked yes)
			(layer "F.Fab")
			(hide yes)
			(effects
				(font
					(size 1 1)
					(thickness 0.15)
				)
			)
		)
		(property "Author" "Antmicro"
			(at 0 0 90)
			(unlocked yes)
			(layer "F.Fab")
			(hide yes)
			(effects
				(font
					(size 1 1)
					(thickness 0.15)
				)
			)
		)
		(property "Color" "Green"
			(at 0 0 90)
			(unlocked yes)
			(layer "F.Fab")
			(hide yes)
			(effects
				(font
					(size 1 1)
					(thickness 0.15)
				)
			)
		)
		(sheetname "/PD and TB DC-DC/")
		(sheetfile "PD_and_TB_DC_DC.kicad_sch")
		(attr smd)
		(fp_line
			(start 0.22 -0.35)
			(end -0.22 -0.35)
			(stroke
				(width 0.15)
				(type solid)
			)
			(layer "F.SilkS")
		)
		(fp_line
			(start -1.18 -0.319)
			(end -1.18 0.321)
			(stroke
				(width 0.15)
				(type solid)
			)
			(layer "F.SilkS")
		)
		(fp_line
			(start 0.105328 0.001008)
			(end 0.24 0.001)
			(stroke
				(width 0.1)
				(type solid)
			)
			(layer "F.SilkS")
		)
		(fp_line
			(start -0.094672 0.001008)
			(end 0.105328 -0.198992)
			(stroke
				(width 0.1)
				(type solid)
			)
			(layer "F.SilkS")
		)
		(fp_line
			(start -0.094672 0.001008)
			(end -0.24 0.001008)
			(stroke
				(width 0.1)
				(type solid)
			)
			(layer "F.SilkS")
		)
		(fp_line
			(start 0.105328 0.201008)
			(end 0.105328 -0.198992)
			(stroke
				(width 0.1)
				(type solid)
			)
			(layer "F.SilkS")
		)
		(fp_line
			(start 0.105328 0.201008)
			(end -0.094672 0.001008)
			(stroke
				(width 0.1)
				(type solid)
			)
			(layer "F.SilkS")
		)
		(fp_line
			(start -0.094672 0.201008)
			(end -0.094672 -0.198992)
			(stroke
				(width 0.1)
				(type solid)
			)
			(layer "F.SilkS")
		)
		(fp_line
			(start 0.22 0.35)
			(end -0.22 0.35)
			(stroke
				(width 0.15)
				(type solid)
			)
			(layer "F.SilkS")
		)
		(fp_rect
			(start 1.25 0.65)
			(end -1.25 -0.65)
			(stroke
				(width 0.05)
				(type solid)
			)
			(fill no)
			(layer "F.CrtYd")
		)
		(fp_line
			(start 0.201 -0.202)
			(end -0.101 0)
			(stroke
				(width 0.15)
				(type solid)
			)
			(layer "F.Fab")
		)
		(fp_line
			(start -0.199 -0.202)
			(end -0.199 0.1)
			(stroke
				(width 0.15)
				(type solid)
			)
			(layer "F.Fab")
		)
		(fp_line
			(start 0.599 0)
			(end 0.201 0)
			(stroke
				(width 0.15)
				(type solid)
			)
			(layer "F.Fab")
		)
		(fp_line
			(start 0.201 0)
			(end 0.201 -0.202)
			(stroke
				(width 0.15)
				(type solid)
			)
			(layer "F.Fab")
		)
		(fp_line
			(start -0.101 0)
			(end 0.201 0.2)
			(stroke
				(width 0.15)
				(type solid)
			)
			(layer "F.Fab")
		)
		(fp_line
			(start -0.199 0)
			(end -0.597 0)
			(stroke
				(width 0.15)
				(type solid)
			)
			(layer "F.Fab")
		)
		(fp_line
			(start 0.201 0.2)
			(end 0.201 0)
			(stroke
				(width 0.15)
				(type solid)
			)
			(layer "F.Fab")
		)
		(fp_line
			(start -0.199 0.2)
			(end -0.199 0.1)
			(stroke
				(width 0.15)
				(type solid)
			)
			(layer "F.Fab")
		)
		(fp_rect
			(start 0.848 0.4)
			(end -0.85 -0.402)
			(stroke
				(width 0.15)
				(type solid)
			)
			(fill no)
			(layer "F.Fab")
		)
		(fp_text user "License: Apache-2.0"
			(at -1.4224 3.599 90)
			(layer "F.Fab")
			(effects
				(font
					(size 0.7 0.7)
					(thickness 0.15)
				)
				(justify left bottom)
			)
		)
		(fp_text user "Author: Antmicro"
			(at -1.4224 4.799 90)
			(layer "F.Fab")
			(effects
				(font
					(size 0.7 0.7)
					(thickness 0.15)
				)
				(justify left bottom)
			)
		)
		(fp_text user "${REFERENCE}"
			(at -1.4224 5.999 90)
			(layer "F.Fab")
			(effects
				(font
					(size 0.7 0.7)
					(thickness 0.15)
				)
				(justify left bottom)
			)
		)
		(pad "1" smd roundrect
			(at -0.7 0 270)
			(size 0.8 1)
			(layers "F.Cu" "F.Mask" "F.Paste")
			(roundrect_rratio 0.2)
			(net 195 "Net-(D4-C)")
			(pinfunction "C")
			(pintype "passive")
		)
		(pad "2" smd roundrect
			(at 0.7 0 270)
			(size 0.8 1)
			(layers "F.Cu" "F.Mask" "F.Paste")
			(roundrect_rratio 0.2)
			(net 399 "Net-(D4-A)")
			(pinfunction "A")
			(pintype "passive")
		)
	)
	(footprint "antmicro-footprints:C_0603_1608Metric"
		(layer "F.Cu")
		(at 153.005001 68.574999 -90)
		(descr "Capacitor SMD 0603")
		(tags "capacitor 0603")
		(property "Reference" "C231"
			(at -12.274999 -20.045 270)
			(layer "F.SilkS")
			(effects
				(font
					(size 0.7 0.7)
					(thickness 0.15)
				)
			)
		)
		(property "Value" "C_10u_10V_X7R_0603"
			(at -1.42757 1.770288 270)
			(layer "F.Fab")
			(effects
				(font
					(size 0.7 0.7)
					(thickness 0.15)
				)
				(justify left bottom)
			)
		)
		(property "Datasheet" "https://www.murata.com/products/productdetail?partno=GRM188Z71A106KA73%23"
			(at 0 0 270)
			(layer "F.Fab")
			(hide yes)
			(effects
				(font
					(size 1.27 1.27)
					(thickness 0.15)
				)
			)
		)
		(property "Description" "SMD Multilayer Ceramic Capacitor,  10µF, 10V, 0603, ±10%, X7R"
			(at 0 0 270)
			(layer "F.Fab")
			(hide yes)
			(effects
				(font
					(size 1.27 1.27)
					(thickness 0.15)
				)
			)
		)
		(property "MPN" "GRM188Z71A106KA73D"
			(at 0 0 270)
			(unlocked yes)
			(layer "F.Fab")
			(hide yes)
			(effects
				(font
					(size 1 1)
					(thickness 0.15)
				)
			)
		)
		(property "Val" "10u"
			(at 0 0 270)
			(unlocked yes)
			(layer "F.Fab")
			(hide yes)
			(effects
				(font
					(size 1 1)
					(thickness 0.15)
				)
			)
		)
		(property "Voltage" "10V"
			(at 0 0 270)
			(unlocked yes)
			(layer "F.Fab")
			(hide yes)
			(effects
				(font
					(size 1 1)
					(thickness 0.15)
				)
			)
		)
		(property "Dielectric" "X7R"
			(at 0 0 270)
			(unlocked yes)
			(layer "F.Fab")
			(hide yes)
			(effects
				(font
					(size 1 1)
					(thickness 0.15)
				)
			)
		)
		(property "Manufacturer" "Murata"
			(at 0 0 270)
			(unlocked yes)
			(layer "F.Fab")
			(hide yes)
			(effects
				(font
					(size 1 1)
					(thickness 0.15)
				)
			)
		)
		(property "License" "Apache-2.0"
			(at 0 0 270)
			(unlocked yes)
			(layer "F.Fab")
			(hide yes)
			(effects
				(font
					(size 1 1)
					(thickness 0.15)
				)
			)
		)
		(property "Author" "Antmicro"
			(at 0 0 270)
			(unlocked yes)
			(layer "F.Fab")
			(hide yes)
			(effects
				(font
					(size 1 1)
					(thickness 0.15)
				)
			)
		)
		(sheetname "/X710-AT2 power/")
		(sheetfile "x710-at2-power.kicad_sch")
		(attr smd)
		(fp_line
			(start -0.15 0.4)
			(end 0.15 0.4)
			(stroke
				(width 0.15)
				(type solid)
			)
			(layer "F.SilkS")
		)
		(fp_line
			(start -0.15 -0.4)
			(end 0.15 -0.4)
			(stroke
				(width 0.15)
				(type solid)
			)
			(layer "F.SilkS")
		)
		(fp_rect
			(start -1.25 -0.65)
			(end 1.25 0.65)
			(stroke
				(width 0.05)
				(type solid)
			)
			(fill no)
			(layer "F.CrtYd")
		)
		(fp_rect
			(start -0.8 -0.4)
			(end 0.8 0.4)
			(stroke
				(width 0.15)
				(type solid)
			)
			(fill no)
			(layer "F.Fab")
		)
		(fp_text user "License: Apache-2.0"
			(at -1.682 5.895 270)
			(layer "F.Fab")
			(effects
				(font
					(size 0.7 0.7)
					(thickness 0.15)
				)
				(justify left bottom)
			)
		)
		(fp_text user "Author: Antmicro"
			(at -1.682 4.894 270)
			(layer "F.Fab")
			(effects
				(font
					(size 0.7 0.7)
					(thickness 0.15)
				)
				(justify left bottom)
			)
		)
		(fp_text user "${REFERENCE}"
			(at -1.682 3.895 270)
			(layer "F.Fab")
			(effects
				(font
					(size 0.7 0.7)
					(thickness 0.15)
				)
				(justify left bottom)
			)
		)
		(pad "1" smd roundrect
			(at -0.7 0 270)
			(size 0.8 1)
			(layers "F.Cu" "F.Mask" "F.Paste")
			(roundrect_rratio 0.2)
			(net 23 "GND")
			(pintype "passive")
		)
		(pad "2" smd roundrect
			(at 0.7 0 270)
			(size 0.8 1)
			(layers "F.Cu" "F.Mask" "F.Paste")
			(roundrect_rratio 0.2)
			(net 7 "+3V3")
			(pintype "passive")
		)
	)
	(footprint "antmicro-footprints:C_0402_1005Metric"
		(layer "F.Cu")
		(at 166 75.4 180)
		(descr "Capacitor SMD 0402")
		(tags "capacitor SMD 0402")
		(property "Reference" "C276"
			(at 1.2 -1.4 180)
			(layer "F.SilkS")
			(effects
				(font
					(size 0.7 0.7)
					(thickness 0.15)
				)
				(justify left bottom)
			)
		)
		(property "Value" "C_100n_0402"
			(at -1.022927 2.155213 180)
			(layer "F.Fab")
			(effects
				(font
					(size 0.7 0.7)
					(thickness 0.15)
				)
				(justify left bottom)
			)
		)
		(property "Datasheet" "https://www.murata.com/products/productdetail?partno=GRM155R61H104KE14%23"
			(at 0 0 180)
			(layer "F.Fab")
			(hide yes)
			(effects
				(font
					(size 1.27 1.27)
					(thickness 0.15)
				)
			)
		)
		(property "Description" "SMD Multilayer Ceramic Capacitor, 0.1 µF, 50 V, 0402 [1005 Metric], ± 10%, X5R, GRM Series"
			(at 0 0 180)
			(layer "F.Fab")
			(hide yes)
			(effects
				(font
					(size 1.27 1.27)
					(thickness 0.15)
				)
			)
		)
		(property "MPN" "GRM155R61H104KE14D"
			(at 0 0 180)
			(unlocked yes)
			(layer "F.Fab")
			(hide yes)
			(effects
				(font
					(size 1 1)
					(thickness 0.15)
				)
			)
		)
		(property "Val" "100n"
			(at 0 0 180)
			(unlocked yes)
			(layer "F.Fab")
			(hide yes)
			(effects
				(font
					(size 1 1)
					(thickness 0.15)
				)
			)
		)
		(property "Voltage" "50V"
			(at 0 0 180)
			(unlocked yes)
			(layer "F.Fab")
			(hide yes)
			(effects
				(font
					(size 1 1)
					(thickness 0.15)
				)
			)
		)
		(property "Dielectric" "X5R"
			(at 0 0 180)
			(unlocked yes)
			(layer "F.Fab")
			(hide yes)
			(effects
				(font
					(size 1 1)
					(thickness 0.15)
				)
			)
		)
		(property "Manufacturer" "Murata"
			(at 0 0 180)
			(unlocked yes)
			(layer "F.Fab")
			(hide yes)
			(effects
				(font
					(size 1 1)
					(thickness 0.15)
				)
			)
		)
		(property "License" "Apache-2.0"
			(at 0 0 180)
			(unlocked yes)
			(layer "F.Fab")
			(hide yes)
			(effects
				(font
					(size 1 1)
					(thickness 0.15)
				)
			)
		)
		(property "Author" "Antmicro"
			(at 0 0 180)
			(unlocked yes)
			(layer "F.Fab")
			(hide yes)
			(effects
				(font
					(size 1 1)
					(thickness 0.15)
				)
			)
		)
		(sheetname "/X710-AT2 Misc/")
		(sheetfile "x710-at2-mics.kicad_sch")
		(attr smd)
		(fp_rect
			(start -0.925 -0.47)
			(end 0.925 0.47)
			(stroke
				(width 0.05)
				(type default)
			)
			(fill no)
			(layer "F.CrtYd")
		)
		(fp_line
			(start 0.504 0.248)
			(end -0.494 0.248)
			(stroke
				(width 0.15)
				(type solid)
			)
			(layer "F.Fab")
		)
		(fp_line
			(start 0.504 -0.25)
			(end 0.504 0.248)
			(stroke
				(width 0.15)
				(type solid)
			)
			(layer "F.Fab")
		)
		(fp_line
			(start -0.494 0.248)
			(end -0.494 -0.25)
			(stroke
				(width 0.15)
				(type solid)
			)
			(layer "F.Fab")
		)
		(fp_line
			(start -0.494 -0.25)
			(end 0.504 -0.25)
			(stroke
				(width 0.15)
				(type solid)
			)
			(layer "F.Fab")
		)
		(fp_text user "${REFERENCE}"
			(at -0.939 4.599 180)
			(layer "F.Fab")
			(effects
				(font
					(size 0.7 0.7)
					(thickness 0.15)
				)
				(justify left bottom)
			)
		)
		(fp_text user "License: Apache-2.0"
			(at -0.939 5.799 180)
			(layer "F.Fab")
			(effects
				(font
					(size 0.7 0.7)
					(thickness 0.15)
				)
				(justify left bottom)
			)
		)
		(fp_text user "Author: Antmicro"
			(at -0.939 3.399 180)
			(layer "F.Fab")
			(effects
				(font
					(size 0.7 0.7)
					(thickness 0.15)
				)
				(justify left bottom)
			)
		)
		(pad "1" smd roundrect
			(at -0.48 0 180)
			(size 0.59 0.64)
			(layers "F.Cu" "F.Mask" "F.Paste")
			(roundrect_rratio 0.25)
			(net 23 "GND")
			(pintype "passive")
		)
		(pad "2" smd roundrect
			(at 0.48 0 180)
			(size 0.59 0.64)
			(layers "F.Cu" "F.Mask" "F.Paste")
			(roundrect_rratio 0.25)
			(net 7 "+3V3")
			(pintype "passive")
		)
	)
	(footprint "antmicro-footprints:R_0402_1005Metric"
		(layer "F.Cu")
		(at 142.309999 93.674999 180)
		(descr "Resistor SMD 0402")
		(tags "resistor SMD 0402")
		(property "Reference" "R146"
			(at -2.190001 -0.025001 180)
			(layer "F.SilkS")
			(effects
				(font
					(size 0.7 0.7)
					(thickness 0.15)
				)
			)
		)
		(property "Value" "R_10k_0402"
			(at -1.011843 1.772047 180)
			(layer "F.Fab")
			(effects
				(font
					(size 0.7 0.7)
					(thickness 0.15)
				)
				(justify left bottom)
			)
		)
		(property "Datasheet" "https://www.bourns.com/docs/product-datasheets/cr.pdf"
			(at 0 0 180)
			(layer "F.Fab")
			(hide yes)
			(effects
				(font
					(size 1.27 1.27)
					(thickness 0.15)
				)
			)
		)
		(property "Description" "SMD Chip Resistor, 10 kohm, ± 1%, 62.5 mW, 0402 [1005 Metric], Thick Film, General Purpose"
			(at 0 0 180)
			(layer "F.Fab")
			(hide yes)
			(effects
				(font
					(size 1.27 1.27)
					(thickness 0.15)
				)
			)
		)
		(property "MPN" "CR0402-FX-1002GLF"
			(at 0 0 180)
			(unlocked yes)
			(layer "F.Fab")
			(hide yes)
			(effects
				(font
					(size 1 1)
					(thickness 0.15)
				)
			)
		)
		(property "Manufacturer" "Bourns"
			(at 0 0 180)
			(unlocked yes)
			(layer "F.Fab")
			(hide yes)
			(effects
				(font
					(size 1 1)
					(thickness 0.15)
				)
			)
		)
		(property "License" "Apache-2.0"
			(at 0 0 180)
			(unlocked yes)
			(layer "F.Fab")
			(hide yes)
			(effects
				(font
					(size 1 1)
					(thickness 0.15)
				)
			)
		)
		(property "Author" "Antmicro"
			(at 0 0 180)
			(unlocked yes)
			(layer "F.Fab")
			(hide yes)
			(effects
				(font
					(size 1 1)
					(thickness 0.15)
				)
			)
		)
		(property "Val" "10k"
			(at 0 0 180)
			(unlocked yes)
			(layer "F.Fab")
			(hide yes)
			(effects
				(font
					(size 1 1)
					(thickness 0.15)
				)
			)
		)
		(property "Tolerance" "1%"
			(at 0 0 180)
			(unlocked yes)
			(layer "F.Fab")
			(hide yes)
			(effects
				(font
					(size 1 1)
					(thickness 0.15)
				)
			)
		)
		(sheetname "/X710-AT2 Misc/")
		(sheetfile "x710-at2-mics.kicad_sch")
		(attr smd)
		(fp_rect
			(start -0.925 -0.47)
			(end 0.925 0.47)
			(stroke
				(width 0.05)
				(type default)
			)
			(fill no)
			(layer "F.CrtYd")
		)
		(fp_rect
			(start -0.5 -0.25)
			(end 0.5 0.25)
			(stroke
				(width 0.15)
				(type solid)
			)
			(fill no)
			(layer "F.Fab")
		)
		(fp_text user "${REFERENCE}"
			(at -0.95 3.168 180)
			(layer "F.Fab")
			(effects
				(font
					(size 0.7 0.7)
					(thickness 0.15)
				)
				(justify left bottom)
			)
		)
		(fp_text user "Author: Antmicro"
			(at -0.95 4.169 180)
			(layer "F.Fab")
			(effects
				(font
					(size 0.7 0.7)
					(thickness 0.15)
				)
				(justify left bottom)
			)
		)
		(fp_text user "License: Apache-2.0"
			(at -0.95 5.169 180)
			(layer "F.Fab")
			(effects
				(font
					(size 0.7 0.7)
					(thickness 0.15)
				)
				(justify left bottom)
			)
		)
		(pad "1" smd roundrect
			(at -0.48 0 180)
			(size 0.59 0.64)
			(layers "F.Cu" "F.Mask" "F.Paste")
			(roundrect_rratio 0.25)
			(net 74 "/X710-AT2 Misc/LAN_PWR_GOOD")
			(pintype "passive")
		)
		(pad "2" smd roundrect
			(at 0.48 0 180)
			(size 0.59 0.64)
			(layers "F.Cu" "F.Mask" "F.Paste")
			(roundrect_rratio 0.25)
			(net 7 "+3V3")
			(pintype "passive")
		)
	)
)
